(kicad_pcb
	(version 20260206)
	(generator "pcbnew")
	(generator_version "10.0")
	(general
		(thickness 1.6)
		(legacy_teardrops no)
	)
	(paper "A4")
	(title_block
		(title "01162023_DA0F0TEBIF0_F0T_Expander_BD_F_brd_V02_OCP.brd")
		(comment 1 "Grand Teton / footprints 137-143 of 9728")
	)
	(layers
		(0 "F.Cu" signal "TOP")
		(4 "In1.Cu" signal "GND")
		(6 "In2.Cu" signal "VCC")
		(8 "In3.Cu" signal "VCC1")
		(10 "In4.Cu" signal "GND1")
		(12 "In5.Cu" signal "IN1")
		(14 "In6.Cu" signal "GND2")
		(16 "In7.Cu" signal "IN2")
		(18 "In8.Cu" signal "GND3")
		(20 "In9.Cu" signal "IN3")
		(22 "In10.Cu" signal "GND4")
		(24 "In11.Cu" signal "IN4")
		(26 "In12.Cu" signal "GND5")
		(28 "In13.Cu" signal "IN5")
		(30 "In14.Cu" signal "GND6")
		(32 "In15.Cu" signal "IN6")
		(34 "In16.Cu" signal "GND7")
		(2 "B.Cu" signal "BOTTOM")
		(9 "F.Adhes" user "F.Adhesive")
		(11 "B.Adhes" user "B.Adhesive")
		(13 "F.Paste" user "Package Geometry/Pastemask Top")
		(15 "B.Paste" user "Package Geometry/Pastemask Bottom")
		(5 "F.SilkS" user "Ref Des/Silkscreen Top")
		(7 "B.SilkS" user "Ref Des/Silkscreen Bottom")
		(1 "F.Mask" user "Board Geometry/Soldermask Top")
		(3 "B.Mask" user "Board Geometry/Soldermask Bottom")
		(17 "Dwgs.User" user "User.Drawings")
		(19 "Cmts.User" user "User.Comments")
		(21 "Eco1.User" user "User.Eco1")
		(23 "Eco2.User" user "User.Eco2")
		(25 "Edge.Cuts" user "Board Geometry/Outline")
		(27 "Margin" user)
		(31 "F.CrtYd" user "Package Geometry/Place Bound Top")
		(29 "B.CrtYd" user "Package Geometry/Place Bound Bottom")
		(35 "F.Fab" user "Ref Des/Assembly Top")
		(33 "B.Fab" user "Ref Des/Assembly Bottom")
	)
	(footprint ""
		(layer "F.Cu")
		(at 254.161036 -37.951156)
		(property "Reference" "Q225"
			(at -0.059436 -1.925574 0)
			(unlocked yes)
			(layer "F.SilkS")
			(effects
				(font
					(size 0.7874 0.5842)
					(thickness 0.1524)
				)
			)
		)
		(property "Value" ""
			(at 0 0 0)
			(layer "F.Fab")
			(effects
				(font
					(size 1.27 1.27)
				)
			)
		)
		(duplicate_pad_numbers_are_jumpers no)
		(fp_line
			(start -1.376172 -1.199896)
			(end -0.508 -1.199896)
			(stroke
				(width 0.1524)
				(type default)
			)
			(layer "F.SilkS")
		)
		(fp_line
			(start -1.376172 1.199896)
			(end -1.376172 -1.199896)
			(stroke
				(width 0.1524)
				(type default)
			)
			(layer "F.SilkS")
		)
		(fp_line
			(start -0.508 -1.199896)
			(end 0 -0.762)
			(stroke
				(width 0.1524)
				(type default)
			)
			(layer "F.SilkS")
		)
		(fp_line
			(start 0 -0.762)
			(end 0.508 -1.199896)
			(stroke
				(width 0.1524)
				(type default)
			)
			(layer "F.SilkS")
		)
		(fp_line
			(start 0.508 -1.199896)
			(end 1.376172 -1.199896)
			(stroke
				(width 0.1524)
				(type default)
			)
			(layer "F.SilkS")
		)
		(fp_line
			(start 1.376172 -1.199896)
			(end 1.376172 1.199896)
			(stroke
				(width 0.1524)
				(type default)
			)
			(layer "F.SilkS")
		)
		(fp_line
			(start 1.376172 1.199896)
			(end -1.376172 1.199896)
			(stroke
				(width 0.1524)
				(type default)
			)
			(layer "F.SilkS")
		)
		(fp_poly
			(pts
				(xy -1.517142 -1.242314) (xy -1.786636 -2.050542) (xy -2.32537 -1.511554)
			)
			(stroke
				(width 0)
				(type default)
			)
			(fill yes)
			(layer "F.SilkS")
		)
		(fp_line
			(start -0.674878 -1.100074)
			(end 0.674878 -1.100074)
			(stroke
				(width 0.1)
				(type default)
			)
			(layer "F.Fab")
		)
		(fp_line
			(start -0.674878 1.100074)
			(end -0.674878 -1.100074)
			(stroke
				(width 0.1)
				(type default)
			)
			(layer "F.Fab")
		)
		(fp_line
			(start 0.674878 -1.100074)
			(end 0.674878 1.100074)
			(stroke
				(width 0.1)
				(type default)
			)
			(layer "F.Fab")
		)
		(fp_line
			(start 0.674878 1.100074)
			(end -0.674878 1.100074)
			(stroke
				(width 0.1)
				(type default)
			)
			(layer "F.Fab")
		)
		(fp_poly
			(pts
				(xy -1.4605 -0.7493) (xy -2.2225 -1.1303) (xy -2.2225 -0.3683)
			)
			(stroke
				(width 0)
				(type default)
			)
			(fill yes)
			(layer "F.Fab")
		)
		(pad "1" smd rect
			(at -0.899922 -0.750062 270)
			(size 0.6096 0.6096)
			(layers "F.Cu" "F.Mask" "F.Paste")
			(net "GND")
		)
		(pad "2" smd rect
			(at -0.899922 0 270)
			(size 0.4064 0.6096)
			(layers "F.Cu" "F.Mask" "F.Paste")
			(net "P3V3_SSD9_PG_G1")
		)
		(pad "3" smd rect
			(at -0.899922 0.750062 270)
			(size 0.6096 0.6096)
			(layers "F.Cu" "F.Mask" "F.Paste")
			(net "PWRGD_P3V3_SSD9_D")
		)
		(pad "4" smd rect
			(at 0.899922 0.750062 270)
			(size 0.6096 0.6096)
			(layers "F.Cu" "F.Mask" "F.Paste")
			(net "GND")
		)
		(pad "5" smd rect
			(at 0.899922 0 270)
			(size 0.4064 0.6096)
			(layers "F.Cu" "F.Mask" "F.Paste")
			(net "P3V3_SSD9_PG_G2")
		)
		(pad "6" smd rect
			(at 0.899922 -0.750062 270)
			(size 0.6096 0.6096)
			(layers "F.Cu" "F.Mask" "F.Paste")
			(net "P3V3_SSD9_PG_G2")
		)
	)
	(footprint ""
		(layer "F.Cu")
		(at 296.79519 -195.32854 90)
		(property "Reference" "R3390"
			(at 0 0 90)
			(layer "F.SilkS")
			(hide yes)
			(effects
				(font
					(size 1.27 1.27)
				)
			)
		)
		(property "Value" ""
			(at 0 0 90)
			(layer "F.Fab")
			(effects
				(font
					(size 1.27 1.27)
				)
			)
		)
		(duplicate_pad_numbers_are_jumpers no)
		(fp_line
			(start 0.7874 -0.4064)
			(end 0.7874 0.4064)
			(stroke
				(width 0.1524)
				(type default)
			)
			(layer "F.SilkS")
		)
		(fp_line
			(start -0.7874 -0.4064)
			(end 0.7874 -0.4064)
			(stroke
				(width 0.1524)
				(type default)
			)
			(layer "F.SilkS")
		)
		(fp_line
			(start 0.7874 0.4064)
			(end -0.7874 0.4064)
			(stroke
				(width 0.1524)
				(type default)
			)
			(layer "F.SilkS")
		)
		(fp_line
			(start -0.7874 0.4064)
			(end -0.7874 -0.4064)
			(stroke
				(width 0.1524)
				(type default)
			)
			(layer "F.SilkS")
		)
		(fp_line
			(start -0.12065 -0.305054)
			(end -0.12065 -0.2794)
			(stroke
				(width 0.1)
				(type default)
			)
			(layer "F.Fab")
		)
		(fp_line
			(start -0.67945 -0.305054)
			(end -0.12065 -0.305054)
			(stroke
				(width 0.1)
				(type default)
			)
			(layer "F.Fab")
		)
		(fp_line
			(start 0.67945 -0.3048)
			(end 0.67945 0.3048)
			(stroke
				(width 0.1)
				(type default)
			)
			(layer "F.Fab")
		)
		(fp_line
			(start 0.12065 -0.3048)
			(end 0.67945 -0.3048)
			(stroke
				(width 0.1)
				(type default)
			)
			(layer "F.Fab")
		)
		(fp_line
			(start 0.12065 -0.2794)
			(end 0.12065 -0.3048)
			(stroke
				(width 0.1)
				(type default)
			)
			(layer "F.Fab")
		)
		(fp_line
			(start -0.12065 -0.2794)
			(end 0.12065 -0.2794)
			(stroke
				(width 0.1)
				(type default)
			)
			(layer "F.Fab")
		)
		(fp_line
			(start 0.120396 0.2794)
			(end -0.12065 0.2794)
			(stroke
				(width 0.1)
				(type default)
			)
			(layer "F.Fab")
		)
		(fp_line
			(start -0.12065 0.2794)
			(end -0.12065 0.3048)
			(stroke
				(width 0.1)
				(type default)
			)
			(layer "F.Fab")
		)
		(fp_line
			(start 0.67945 0.3048)
			(end 0.120396 0.3048)
			(stroke
				(width 0.1)
				(type default)
			)
			(layer "F.Fab")
		)
		(fp_line
			(start 0.120396 0.3048)
			(end 0.120396 0.2794)
			(stroke
				(width 0.1)
				(type default)
			)
			(layer "F.Fab")
		)
		(fp_line
			(start -0.12065 0.3048)
			(end -0.67945 0.3048)
			(stroke
				(width 0.1)
				(type default)
			)
			(layer "F.Fab")
		)
		(fp_line
			(start -0.67945 0.3048)
			(end -0.67945 -0.305054)
			(stroke
				(width 0.1)
				(type default)
			)
			(layer "F.Fab")
		)
		(pad "1" smd circle
			(at -0.40005 0 90)
			(size 0 0)
			(layers "F.Cu" "F.Mask" "F.Paste")
			(net "SPI_BIC1_CS0_R1_N")
		)
		(pad "2" smd circle
			(at 0.40005 0 90)
			(size 0 0)
			(layers "F.Cu" "F.Mask" "F.Paste")
			(net "SPI_BIC1_CS0_R3_N")
		)
	)
	(footprint ""
		(layer "F.Cu")
		(at 145.522442 -252.356874 -90)
		(property "Reference" "R1292"
			(at 0 0 270)
			(layer "F.SilkS")
			(hide yes)
			(effects
				(font
					(size 1.27 1.27)
				)
			)
		)
		(property "Value" ""
			(at 0 0 270)
			(layer "F.Fab")
			(effects
				(font
					(size 1.27 1.27)
				)
			)
		)
		(duplicate_pad_numbers_are_jumpers no)
		(fp_line
			(start -0.7874 0.4064)
			(end -0.7874 -0.4064)
			(stroke
				(width 0.1524)
				(type default)
			)
			(layer "F.SilkS")
		)
		(fp_line
			(start 0.7874 0.4064)
			(end -0.7874 0.4064)
			(stroke
				(width 0.1524)
				(type default)
			)
			(layer "F.SilkS")
		)
		(fp_line
			(start -0.7874 -0.4064)
			(end 0.7874 -0.4064)
			(stroke
				(width 0.1524)
				(type default)
			)
			(layer "F.SilkS")
		)
		(fp_line
			(start 0.7874 -0.4064)
			(end 0.7874 0.4064)
			(stroke
				(width 0.1524)
				(type default)
			)
			(layer "F.SilkS")
		)
		(fp_line
			(start -0.67945 0.3048)
			(end -0.67945 -0.305054)
			(stroke
				(width 0.1)
				(type default)
			)
			(layer "F.Fab")
		)
		(fp_line
			(start -0.12065 0.3048)
			(end -0.67945 0.3048)
			(stroke
				(width 0.1)
				(type default)
			)
			(layer "F.Fab")
		)
		(fp_line
			(start 0.120396 0.3048)
			(end 0.120396 0.2794)
			(stroke
				(width 0.1)
				(type default)
			)
			(layer "F.Fab")
		)
		(fp_line
			(start 0.67945 0.3048)
			(end 0.120396 0.3048)
			(stroke
				(width 0.1)
				(type default)
			)
			(layer "F.Fab")
		)
		(fp_line
			(start -0.12065 0.2794)
			(end -0.12065 0.3048)
			(stroke
				(width 0.1)
				(type default)
			)
			(layer "F.Fab")
		)
		(fp_line
			(start 0.120396 0.2794)
			(end -0.12065 0.2794)
			(stroke
				(width 0.1)
				(type default)
			)
			(layer "F.Fab")
		)
		(fp_line
			(start -0.12065 -0.2794)
			(end 0.12065 -0.2794)
			(stroke
				(width 0.1)
				(type default)
			)
			(layer "F.Fab")
		)
		(fp_line
			(start 0.12065 -0.2794)
			(end 0.12065 -0.3048)
			(stroke
				(width 0.1)
				(type default)
			)
			(layer "F.Fab")
		)
		(fp_line
			(start 0.12065 -0.3048)
			(end 0.67945 -0.3048)
			(stroke
				(width 0.1)
				(type default)
			)
			(layer "F.Fab")
		)
		(fp_line
			(start 0.67945 -0.3048)
			(end 0.67945 0.3048)
			(stroke
				(width 0.1)
				(type default)
			)
			(layer "F.Fab")
		)
		(fp_line
			(start -0.67945 -0.305054)
			(end -0.12065 -0.305054)
			(stroke
				(width 0.1)
				(type default)
			)
			(layer "F.Fab")
		)
		(fp_line
			(start -0.12065 -0.305054)
			(end -0.12065 -0.2794)
			(stroke
				(width 0.1)
				(type default)
			)
			(layer "F.Fab")
		)
		(pad "1" smd circle
			(at -0.40005 0 270)
			(size 0 0)
			(layers "F.Cu" "F.Mask" "F.Paste")
			(net "GND")
		)
		(pad "2" smd circle
			(at 0.40005 0 270)
			(size 0 0)
			(layers "F.Cu" "F.Mask" "F.Paste")
			(net "PEX1_MODE_SEL3")
		)
	)
	(footprint ""
		(layer "F.Cu")
		(at 11.1379 -264.586466)
		(property "Reference" "R6129"
			(at 0 0 0)
			(layer "F.SilkS")
			(hide yes)
			(effects
				(font
					(size 1.27 1.27)
				)
			)
		)
		(property "Value" ""
			(at 0 0 0)
			(layer "F.Fab")
			(effects
				(font
					(size 1.27 1.27)
				)
			)
		)
		(duplicate_pad_numbers_are_jumpers no)
		(fp_line
			(start -2.576322 -1.1303)
			(end 2.576322 -1.1303)
			(stroke
				(width 0.1524)
				(type default)
			)
			(layer "F.SilkS")
		)
		(fp_line
			(start -2.576322 1.1303)
			(end -2.576322 -1.1303)
			(stroke
				(width 0.1524)
				(type default)
			)
			(layer "F.SilkS")
		)
		(fp_line
			(start 2.576322 -1.1303)
			(end 2.576322 1.1303)
			(stroke
				(width 0.1524)
				(type default)
			)
			(layer "F.SilkS")
		)
		(fp_line
			(start 2.576322 1.1303)
			(end -2.576322 1.1303)
			(stroke
				(width 0.1524)
				(type default)
			)
			(layer "F.SilkS")
		)
		(fp_line
			(start -1.649984 -0.899922)
			(end -1.649984 0.899922)
			(stroke
				(width 0.1)
				(type default)
			)
			(layer "F.Fab")
		)
		(fp_line
			(start -1.649984 0.899922)
			(end 1.649984 0.899922)
			(stroke
				(width 0.1)
				(type default)
			)
			(layer "F.Fab")
		)
		(fp_line
			(start 1.649984 -0.899922)
			(end -1.649984 -0.899922)
			(stroke
				(width 0.1)
				(type default)
			)
			(layer "F.Fab")
		)
		(fp_line
			(start 1.649984 0.899922)
			(end 1.649984 -0.899922)
			(stroke
				(width 0.1)
				(type default)
			)
			(layer "F.Fab")
		)
		(pad "1A" smd rect
			(at -1.700022 0)
			(size 1.4986 2.0066)
			(layers "F.Cu" "F.Mask" "F.Paste")
			(net "P1V25_PEX0")
		)
		(pad "1B" smd rect
			(at -1.077722 0)
			(size 0.254 0.508)
			(layers "F.Cu" "F.Mask" "F.Paste")
			(net "P1V25_PEX0")
		)
		(pad "2A" smd rect
			(at 1.700022 0)
			(size 1.4986 2.0066)
			(layers "F.Cu" "F.Mask" "F.Paste")
			(net "P1V25_SERDES_VDDPLL_PEX0")
		)
		(pad "2B" smd rect
			(at 1.077722 0)
			(size 0.254 0.508)
			(layers "F.Cu" "F.Mask" "F.Paste")
			(net "P1V25_SERDES_VDDPLL_PEX0")
		)
	)
	(footprint ""
		(layer "F.Cu")
		(at 155.380436 -136.729724)
		(property "Reference" "C245"
			(at 0 0 0)
			(layer "F.SilkS")
			(hide yes)
			(effects
				(font
					(size 1.27 1.27)
				)
			)
		)
		(property "Value" ""
			(at 0 0 0)
			(layer "F.Fab")
			(effects
				(font
					(size 1.27 1.27)
				)
			)
		)
		(duplicate_pad_numbers_are_jumpers no)
		(fp_line
			(start -0.299974 -0.150114)
			(end 0.299974 -0.150114)
			(stroke
				(width 0.1)
				(type default)
			)
			(layer "F.Fab")
		)
		(fp_line
			(start -0.299974 0.150114)
			(end -0.299974 -0.150114)
			(stroke
				(width 0.1)
				(type default)
			)
			(layer "F.Fab")
		)
		(fp_line
			(start 0.299974 -0.150114)
			(end 0.299974 0.150114)
			(stroke
				(width 0.1)
				(type default)
			)
			(layer "F.Fab")
		)
		(fp_line
			(start 0.299974 0.150114)
			(end -0.299974 0.150114)
			(stroke
				(width 0.1)
				(type default)
			)
			(layer "F.Fab")
		)
		(pad "1" smd rect
			(at -0.2667 0)
			(size 0.3048 0.381)
			(layers "F.Cu" "F.Mask" "F.Paste")
			(net "P5E_PEX1_STN1_TX_DP<31>")
		)
		(pad "2" smd rect
			(at 0.2667 0)
			(size 0.3048 0.381)
			(layers "F.Cu" "F.Mask" "F.Paste")
			(net "P5E_PEX1_STN1_TX_C_DP<31>")
		)
	)
	(footprint ""
		(layer "F.Cu")
		(at 448.436238 -95.264224 -90)
		(property "Reference" "C2860"
			(at 0 0 270)
			(layer "F.SilkS")
			(hide yes)
			(effects
				(font
					(size 1.27 1.27)
				)
			)
		)
		(property "Value" ""
			(at 0 0 270)
			(layer "F.Fab")
			(effects
				(font
					(size 1.27 1.27)
				)
			)
		)
		(duplicate_pad_numbers_are_jumpers no)
		(fp_line
			(start -0.7874 0.4064)
			(end -0.7874 -0.4064)
			(stroke
				(width 0.1524)
				(type default)
			)
			(layer "F.SilkS")
		)
		(fp_line
			(start 0.7874 0.4064)
			(end -0.7874 0.4064)
			(stroke
				(width 0.1524)
				(type default)
			)
			(layer "F.SilkS")
		)
		(fp_line
			(start -0.7874 -0.4064)
			(end 0.7874 -0.4064)
			(stroke
				(width 0.1524)
				(type default)
			)
			(layer "F.SilkS")
		)
		(fp_line
			(start 0.7874 -0.4064)
			(end 0.7874 0.4064)
			(stroke
				(width 0.1524)
				(type default)
			)
			(layer "F.SilkS")
		)
		(fp_line
			(start -0.67945 0.3048)
			(end -0.67945 -0.305054)
			(stroke
				(width 0.1)
				(type default)
			)
			(layer "F.Fab")
		)
		(fp_line
			(start -0.12065 0.3048)
			(end -0.67945 0.3048)
			(stroke
				(width 0.1)
				(type default)
			)
			(layer "F.Fab")
		)
		(fp_line
			(start 0.120396 0.3048)
			(end 0.120396 0.2794)
			(stroke
				(width 0.1)
				(type default)
			)
			(layer "F.Fab")
		)
		(fp_line
			(start 0.67945 0.3048)
			(end 0.120396 0.3048)
			(stroke
				(width 0.1)
				(type default)
			)
			(layer "F.Fab")
		)
		(fp_line
			(start -0.12065 0.2794)
			(end -0.12065 0.3048)
			(stroke
				(width 0.1)
				(type default)
			)
			(layer "F.Fab")
		)
		(fp_line
			(start 0.120396 0.2794)
			(end -0.12065 0.2794)
			(stroke
				(width 0.1)
				(type default)
			)
			(layer "F.Fab")
		)
		(fp_line
			(start -0.12065 -0.2794)
			(end 0.12065 -0.2794)
			(stroke
				(width 0.1)
				(type default)
			)
			(layer "F.Fab")
		)
		(fp_line
			(start 0.12065 -0.2794)
			(end 0.12065 -0.3048)
			(stroke
				(width 0.1)
				(type default)
			)
			(layer "F.Fab")
		)
		(fp_line
			(start 0.12065 -0.3048)
			(end 0.67945 -0.3048)
			(stroke
				(width 0.1)
				(type default)
			)
			(layer "F.Fab")
		)
		(fp_line
			(start 0.67945 -0.3048)
			(end 0.67945 0.3048)
			(stroke
				(width 0.1)
				(type default)
			)
			(layer "F.Fab")
		)
		(fp_line
			(start -0.67945 -0.305054)
			(end -0.12065 -0.305054)
			(stroke
				(width 0.1)
				(type default)
			)
			(layer "F.Fab")
		)
		(fp_line
			(start -0.12065 -0.305054)
			(end -0.12065 -0.2794)
			(stroke
				(width 0.1)
				(type default)
			)
			(layer "F.Fab")
		)
		(pad "1" smd circle
			(at -0.40005 0 270)
			(size 0 0)
			(layers "F.Cu" "F.Mask" "F.Paste")
			(net "P12V_NIC7_EN_R")
		)
		(pad "2" smd circle
			(at 0.40005 0 270)
			(size 0 0)
			(layers "F.Cu" "F.Mask" "F.Paste")
			(net "GND")
		)
	)
	(footprint ""
		(layer "F.Cu")
		(at 325.596504 -237.133892 180)
		(property "Reference" "R1783"
			(at 0 0 180)
			(layer "F.SilkS")
			(hide yes)
			(effects
				(font
					(size 1.27 1.27)
				)
			)
		)
		(property "Value" ""
			(at 0 0 180)
			(layer "F.Fab")
			(effects
				(font
					(size 1.27 1.27)
				)
			)
		)
		(duplicate_pad_numbers_are_jumpers no)
		(fp_line
			(start 0.7874 0.4064)
			(end -0.7874 0.4064)
			(stroke
				(width 0.1524)
				(type default)
			)
			(layer "F.SilkS")
		)
		(fp_line
			(start 0.7874 -0.4064)
			(end 0.7874 0.4064)
			(stroke
				(width 0.1524)
				(type default)
			)
			(layer "F.SilkS")
		)
		(fp_line
			(start -0.7874 0.4064)
			(end -0.7874 -0.4064)
			(stroke
				(width 0.1524)
				(type default)
			)
			(layer "F.SilkS")
		)
		(fp_line
			(start -0.7874 -0.4064)
			(end 0.7874 -0.4064)
			(stroke
				(width 0.1524)
				(type default)
			)
			(layer "F.SilkS")
		)
		(fp_line
			(start 0.67945 0.3048)
			(end 0.120396 0.3048)
			(stroke
				(width 0.1)
				(type default)
			)
			(layer "F.Fab")
		)
		(fp_line
			(start 0.67945 -0.3048)
			(end 0.67945 0.3048)
			(stroke
				(width 0.1)
				(type default)
			)
			(layer "F.Fab")
		)
		(fp_line
			(start 0.12065 -0.2794)
			(end 0.12065 -0.3048)
			(stroke
				(width 0.1)
				(type default)
			)
			(layer "F.Fab")
		)
		(fp_line
			(start 0.12065 -0.3048)
			(end 0.67945 -0.3048)
			(stroke
				(width 0.1)
				(type default)
			)
			(layer "F.Fab")
		)
		(fp_line
			(start 0.120396 0.3048)
			(end 0.120396 0.2794)
			(stroke
				(width 0.1)
				(type default)
			)
			(layer "F.Fab")
		)
		(fp_line
			(start 0.120396 0.2794)
			(end -0.12065 0.2794)
			(stroke
				(width 0.1)
				(type default)
			)
			(layer "F.Fab")
		)
		(fp_line
			(start -0.12065 0.3048)
			(end -0.67945 0.3048)
			(stroke
				(width 0.1)
				(type default)
			)
			(layer "F.Fab")
		)
		(fp_line
			(start -0.12065 0.2794)
			(end -0.12065 0.3048)
			(stroke
				(width 0.1)
				(type default)
			)
			(layer "F.Fab")
		)
		(fp_line
			(start -0.12065 -0.2794)
			(end 0.12065 -0.2794)
			(stroke
				(width 0.1)
				(type default)
			)
			(layer "F.Fab")
		)
		(fp_line
			(start -0.12065 -0.305054)
			(end -0.12065 -0.2794)
			(stroke
				(width 0.1)
				(type default)
			)
			(layer "F.Fab")
		)
		(fp_line
			(start -0.67945 0.3048)
			(end -0.67945 -0.305054)
			(stroke
				(width 0.1)
				(type default)
			)
			(layer "F.Fab")
		)
		(fp_line
			(start -0.67945 -0.305054)
			(end -0.12065 -0.305054)
			(stroke
				(width 0.1)
				(type default)
			)
			(layer "F.Fab")
		)
		(pad "1" smd circle
			(at -0.40005 0 180)
			(size 0 0)
			(layers "F.Cu" "F.Mask" "F.Paste")
			(net "PRSNT_GPU_ISO_N")
		)
		(pad "2" smd circle
			(at 0.40005 0 180)
			(size 0 0)
			(layers "F.Cu" "F.Mask" "F.Paste")
			(net "PRSNT_GPU_ISO_R_N")
		)
	)
)
